FILE_TYPE = CONNECTIVITY;
{Allegro Design Entry HDL 17.4-2019 S026 (4007227) 1/17/2022}
"PAGE_NUMBER" = 33;
0"NC";
1"GND\g";
2"GND\g";
%"GENOA_SP5"
"40","(-4750,3750)","1","pure_quanta","I4";
;
LOCATION"U25"
$SEC"40"
CDS_SEC"40"
PART_TYPE"SMLF"
MATERIAL"IO"
VALUE"SOCKET6096_13568-001"
CDS_LMAN_SYM_OUTLINE"-400,3350,400,-3350"
CDS_LIB"pure_quanta"
NEEDS_NO_SIZE"TRUE"
PART_NUMBER"DGA^6000030";
"VSS_V68"
$PN"V68"1;
"VSS_BV42"
$PN"BV42"1;
"VSS_CT52"
$PN"CT52"1;
"VSS_CM50"
$PN"CM50"1;
"VSS_K59"
$PN"K59"1;
"VSS_DA56"
$PN"DA56"1;
"VSS_CG42"
$PN"CG42"1;
"VSS_AE4"
$PN"AE4"1;
"VSS_AH33"
$PN"AH33"1;
"VSS_BW25"
$PN"BW25"1;
"VSS_CU58"
$PN"CU58"1;
"VSS_P25"
$PN"P25"1;
"VSS_P68"
$PN"P68"1;
"VSS_AN20"
$PN"AN20"1;
"VSS_CC22"
$PN"CC22"1;
"VSS_CF46"
$PN"CF46"1;
"VSS_V27"
$PN"V27"1;
"VSS_AA42"
$PN"AA42"1;
"VSS_AD31"
$PN"AD31"1;
"VSS_AJ13"
$PN"AJ13"1;
"VSS_AA72"
$PN"AA72"1;
"VSS_CK10"
$PN"CK10"1;
"VSS_CN54"
$PN"CN54"1;
"VSS_K23"
$PN"K23"1;
"VSS_AM37"
$PN"AM37"1;
"VSS_CB44"
$PN"CB44"1;
"VSS_CK31"
$PN"CK31"1;
"VSS_CY57"
$PN"CY57"1;
"VSS_DJ73"
$PN"DJ73"1;
"VSS_DJ68"
$PN"DJ68"1;
"VSS_DJ66"
$PN"DJ66"1;
"VSS_DJ63"
$PN"DJ63"1;
"VSS_DJ61"
$PN"DJ61"1;
"VSS_DJ59"
$PN"DJ59"1;
"VSS_DJ49"
$PN"DJ49"1;
"VSS_DJ43"
$PN"DJ43"1;
"VSS_DJ19"
$PN"DJ19"1;
"VSS_DJ15"
$PN"DJ15"1;
"VSS_DJ7"
$PN"DJ7"1;
"VSS_DH70"
$PN"DH70"1;
"VSS_DH68"
$PN"DH68"1;
"VSS_DH59"
$PN"DH59"1;
"VSS_DH55"
$PN"DH55"1;
"VSS_DH52"
$PN"DH52"1;
"VSS_DH49"
$PN"DH49"1;
"VSS_DH46"
$PN"DH46"1;
"VSS_DH43"
$PN"DH43"1;
"VSS_DH39"
$PN"DH39"1;
"VSS_DG75"
$PN"DG75"1;
"VSS_DG74"
$PN"DG74"1;
"VSS_DG70"
$PN"DG70"1;
"VSS_DG69"
$PN"DG69"1;
"VSS_DG68"
$PN"DG68"1;
"VSS_DG67"
$PN"DG67"1;
"VSS_DG66"
$PN"DG66"1;
"VSS_DG60"
$PN"DG60"1;
"VSS_DG59"
$PN"DG59"1;
"VSS_DG56"
$PN"DG56"1;
"VSS_DG55"
$PN"DG55"1;
"VSS_DG52"
$PN"DG52"1;
"VSS_DG49"
$PN"DG49"1;
"VSS_DG46"
$PN"DG46"1;
"VSS_DG27"
$PN"DG27"1;
"VSS_DG24"
$PN"DG24"1;
"VSS_DG21"
$PN"DG21"1;
"VSS_DG20"
$PN"DG20"1;
"VSS_DG18"
$PN"DG18"1;
"VSS_DG16"
$PN"DG16"1;
"VSS_DG15"
$PN"DG15"1;
"VSS_DG7"
$PN"DG7"1;
"VSS_DG6"
$PN"DG6"1;
"VSS_DG2"
$PN"DG2"1;
"VSS_DG1"
$PN"DG1"1;
"VSS_DF73"
$PN"DF73"1;
"VSS_DF72"
$PN"DF72"1;
"VSS_DF71"
$PN"DF71"1;
"VSS_DF65"
$PN"DF65"1;
"VSS_DF64"
$PN"DF64"1;
"VSS_DF63"
$PN"DF63"1;
"VSS_DF61"
$PN"DF61"1;
"VSS_DF59"
$PN"DF59"1;
"VSS_DF58"
$PN"DF58"1;
"VSS_DF57"
$PN"DF57"1;
"VSS_DF56"
$PN"DF56"1;
"VSS_DF52"
$PN"DF52"1;
"VSS_DF51"
$PN"DF51"1;
"VSS_DF50"
$PN"DF50"1;
"VSS_DF49"
$PN"DF49"1;
"VSS_DF48"
$PN"DF48"1;
"VSS_DF47"
$PN"DF47"1;
"VSS_DF46"
$PN"DF46"1;
"VSS_DF45"
$PN"DF45"1;
"VSS_DF44"
$PN"DF44"1;
"VSS_DF42"
$PN"DF42"1;
"VSS_DF39"
$PN"DF39"1;
"VSS_DF37"
$PN"DF37"1;
"VSS_DF35"
$PN"DF35"1;
"VSS_DF32"
$PN"DF32"1;
"VSS_DF29"
$PN"DF29"1;
"VSS_DF26"
$PN"DF26"1;
"VSS_DF23"
$PN"DF23"1;
"VSS_DF22"
$PN"DF22"1;
"VSS_DF20"
$PN"DF20"1;
"VSS_DF13"
$PN"DF13"2;
"VSS_DF12"
$PN"DF12"2;
"VSS_DF11"
$PN"DF11"2;
"VSS_DF10"
$PN"DF10"2;
"VSS_DF8"
$PN"DF8"2;
"VSS_DF6"
$PN"DF6"2;
"VSS_DF5"
$PN"DF5"2;
"VSS_DE68"
$PN"DE68"2;
"VSS_DE63"
$PN"DE63"2;
"VSS_DE61"
$PN"DE61"2;
"VSS_DE56"
$PN"DE56"2;
"VSS_DE33"
$PN"DE33"2;
"VSS_DE29"
$PN"DE29"2;
"VSS_DE26"
$PN"DE26"2;
"VSS_DE8"
$PN"DE8"2;
"VSS_DE6"
$PN"DE6"2;
"VSS_DE1"
$PN"DE1"2;
"VSS_DD73"
$PN"DD73"2;
"VSS_DD71"
$PN"DD71"2;
"VSS_DD68"
$PN"DD68"2;
"VSS_DD66"
$PN"DD66"2;
"VSS_DD53"
$PN"DD53"2;
"VSS_DD52"
$PN"DD52"2;
"VSS_DD50"
$PN"DD50"2;
"VSS_DD49"
$PN"DD49"2;
"VSS_DD47"
$PN"DD47"2;
"VSS_DD46"
$PN"DD46"2;
"VSS_DD44"
$PN"DD44"2;
"VSS_DD37"
$PN"DD37"2;
"VSS_DD36"
$PN"DD36"2;
"VSS_DD35"
$PN"DD35"2;
"VSS_DD33"
$PN"DD33"2;
"VSS_DD32"
$PN"DD32"2;
"VSS_DD30"
$PN"DD30"2;
"VSS_DD29"
$PN"DD29"2;
"VSS_DD19"
$PN"DD19"2;
"VSS_DD17"
$PN"DD17"2;
"VSS_DD15"
$PN"DD15"2;
"VSS_DD12"
$PN"DD12"2;
"VSS_DD10"
$PN"DD10"2;
"VSS_DD8"
$PN"DD8"2;
"VSS_DD5"
$PN"DD5"2;
"VSS_DC68"
$PN"DC68"2;
"VSS_DC65"
$PN"DC65"2;
"VSS_DC63"
$PN"DC63"2;
"VSS_DC61"
$PN"DC61"2;
"VSS_DC58"
$PN"DC58"2;
"VSS_DC56"
$PN"DC56"2;
"VSS_DC54"
$PN"DC54"2;
"VSS_DC42"
$PN"DC42"2;
"VSS_DC34"
$PN"DC34"2;
"VSS_DC31"
$PN"DC31"2;
"VSS_DC28"
$PN"DC28"2;
"VSS_DC25"
$PN"DC25"2;
"VSS_DC22"
$PN"DC22"2;
"VSS_DC20"
$PN"DC20"2;
"VSS_DC18"
$PN"DC18"2;
"VSS_DC11"
$PN"DC11"2;
"VSS_DC8"
$PN"DC8"2;
"VSS_DC6"
$PN"DC6"2;
"VSS_DC4"
$PN"DC4"2;
"VSS_DC1"
$PN"DC1"2;
"VSS_DB73"
$PN"DB73"2;
"VSS_DB68"
$PN"DB68"2;
"VSS_DB66"
$PN"DB66"2;
"VSS_DB61"
$PN"DB61"2;
"VSS_DB45"
$PN"DB45"2;
"VSS_DB42"
$PN"DB42"2;
"VSS_DB39"
$PN"DB39"2;
"VSS_DB37"
$PN"DB37"2;
"VSS_DB34"
$PN"DB34"2;
"VSS_DB31"
$PN"DB31"2;
"VSS_DB28"
$PN"DB28"2;
"VSS_DB10"
$PN"DB10"2;
"VSS_DB8"
$PN"DB8"2;
"VSS_DB3"
$PN"DB3"2;
"VSS_DA75"
$PN"DA75"2;
"VSS_DA72"
$PN"DA72"2;
"VSS_DH66"
$PN"DH66"1;
"VSS_DH64"
$PN"DH64"1;
"VSS_DH63"
$PN"DH63"1;
"VSS_DH61"
$PN"DH61"1;
"VSS_DH37"
$PN"DH37"1;
"VSS_DH18"
$PN"DH18"1;
"VSS_DH11"
$PN"DH11"1;
"VSS_DH5"
$PN"DH5"1;
"VSS_DG65"
$PN"DG65"1;
"VSS_DG63"
$PN"DG63"1;
"VSS_DG62"
$PN"DG62"1;
"VSS_DG61"
$PN"DG61"1;
"VSS_DG43"
$PN"DG43"1;
"VSS_DG41"
$PN"DG41"1;
"VSS_DG33"
$PN"DG33"1;
"VSS_DG30"
$PN"DG30"1;
"VSS_DG14"
$PN"DG14"1;
"VSS_DG13"
$PN"DG13"1;
"VSS_DG9"
$PN"DG9"1;
"VSS_DG8"
$PN"DG8"1;
"VSS_DF70"
$PN"DF70"1;
"VSS_DF68"
$PN"DF68"1;
"VSS_DF66"
$PN"DF66"1;
"VSS_DF54"
$PN"DF54"1;
"VSS_DF53"
$PN"DF53"1;
"VSS_DF43"
$PN"DF43"1;
"VSS_DF19"
$PN"DF19"2;
"VSS_DF18"
$PN"DF18"2;
"VSS_DF17"
$PN"DF17"2;
"VSS_DF15"
$PN"DF15"2;
"VSS_DF4"
$PN"DF4"2;
"VSS_DF3"
$PN"DF3"2;
"VSS_DE75"
$PN"DE75"2;
"VSS_DE70"
$PN"DE70"2;
"VSS_DE23"
$PN"DE23"2;
"VSS_DE20"
$PN"DE20"2;
"VSS_DE15"
$PN"DE15"2;
"VSS_DE13"
$PN"DE13"2;
"VSS_DD64"
$PN"DD64"2;
"VSS_DD61"
$PN"DD61"2;
"VSS_DD59"
$PN"DD59"2;
"VSS_DD57"
$PN"DD57"2;
"VSS_DD43"
$PN"DD43"2;
"VSS_DD41"
$PN"DD41"2;
"VSS_DD40"
$PN"DD40"2;
"VSS_DD39"
$PN"DD39"2;
"VSS_DD27"
$PN"DD27"2;
"VSS_DD26"
$PN"DD26"2;
"VSS_DD24"
$PN"DD24"2;
"VSS_DD23"
$PN"DD23"2;
"VSS_DD3"
$PN"DD3"2;
"VSS_DC75"
$PN"DC75"2;
"VSS_DC72"
$PN"DC72"2;
"VSS_DC70"
$PN"DC70"2;
"VSS_DC51"
$PN"DC51"2;
"VSS_DC48"
$PN"DC48"2;
"VSS_DC45"
$PN"DC45"2;
"VSS_DC15"
$PN"DC15"2;
"VSS_DC13"
$PN"DC13"2;
"VSS_DB59"
$PN"DB59"2;
"VSS_DB54"
$PN"DB54"2;
"VSS_DB51"
$PN"DB51"2;
"VSS_DB48"
$PN"DB48"2;
"VSS_DB25"
$PN"DB25"2;
"VSS_DB22"
$PN"DB22"2;
"VSS_DB17"
$PN"DB17"2;
"VSS_DB15"
$PN"DB15"2;
%"UNIVERSAL_GND"
"1","(-1300,4475)","1","pure_quanta_power","I5";
;
CDS_LIB"pure_quanta_power"
HDL_POWER"GND";
"A"1;
%"UNIVERSAL_GND"
"1","(-1875,3025)","1","pure_quanta_power","I6";
;
CDS_LIB"pure_quanta_power"
HDL_POWER"GND";
"A"2;
END.
